(kicad_pcb
	(version 20211014)
	(generator pcbnew)
	(general
    (thickness 1.6)
  )
	(paper "A4")
	(title_block
    (title "SA800U (Snapdragon 845) Baseboard")
    (date "2023-10-19")
    (rev "1.0.3")
    (company "Antmicro Ltd.")
    (comment 1 "www.antmicro.com")
		(comment 9 "footprints 97-100 of 589")
	)
	(layers
    (0 "F.Cu" signal)
    (1 "In1.Cu" power)
    (2 "In2.Cu" signal)
    (3 "In3.Cu" signal)
    (4 "In4.Cu" power)
    (31 "B.Cu" signal)
    (32 "B.Adhes" user "B.Adhesive")
    (33 "F.Adhes" user "F.Adhesive")
    (34 "B.Paste" user)
    (35 "F.Paste" user)
    (36 "B.SilkS" user "B.Silkscreen")
    (37 "F.SilkS" user "F.Silkscreen")
    (38 "B.Mask" user)
    (39 "F.Mask" user)
    (40 "Dwgs.User" user "User.Drawings")
    (41 "Cmts.User" user "User.Comments")
    (42 "Eco1.User" user "User.Eco1")
    (43 "Eco2.User" user "User.Eco2")
    (44 "Edge.Cuts" user)
    (45 "Margin" user)
    (46 "B.CrtYd" user "B.Courtyard")
    (47 "F.CrtYd" user "F.Courtyard")
    (48 "B.Fab" user)
    (49 "F.Fab" user)
  )
	(footprint "sa800u-baseboard-hw-footprints:AP62301WU-7-TSOT23-6" (layer "F.Cu")
    (tedit 6215EA50)
    (at 74.59 117.65 90)
    (property "Author" "Antmicro")
    (property "License" "Apache-2.0")
    (property "MPN" "AP62301WU-7")
    (property "Manufacturer" "Diodes Incorporated")
    (property "Sheetfile" "psu.kicad_sch")
    (property "Sheetname" "PSU")
    (attr smd)
    (fp_text reference "U22" (at 1.62 -0.18 180) (layer "F.SilkS")
      (effects (font (size 0.7 0.7) (thickness 0.15)) (justify left bottom))
    )
    (fp_text value "AP62301WU-7" (at -0.005 2.6 90) (layer "F.Fab")
      (effects (font (size 0.7 0.7) (thickness 0.15)) (justify left bottom))
    )
    (fp_text user "Author: Antmicro" (at -1.893 7.368 90) (layer "F.Fab") hide
      (effects (font (size 0.7 0.7) (thickness 0.15)) (justify left bottom))
    )
    (fp_text user "License: Apache-2.0" (at -1.893 4.967 90) (layer "F.Fab") hide
      (effects (font (size 0.7 0.7) (thickness 0.15)) (justify left bottom))
    )
    (fp_text user "${REFERENCE}" (at -1.893 6.168 90) (layer "F.Fab") hide
      (effects (font (size 0.7 0.7) (thickness 0.15)) (justify left bottom))
    )
    (fp_line (start 1.48 -0.72) (end 1.479 0.73) (layer "F.SilkS") (width 0.15))
    (fp_line (start 1.48 -0.72) (end 1.38 -0.72) (layer "F.SilkS") (width 0.15))
    (fp_line (start -1.4805 0.725) (end -1.3905 0.725) (layer "F.SilkS") (width 0.15))
    (fp_line (start 1.479 0.73) (end 1.38 0.73) (layer "F.SilkS") (width 0.15))
    (fp_line (start -1.4795 -0.725) (end -1.3905 -0.725) (layer "F.SilkS") (width 0.15))
    (fp_line (start -1.4805 0.725) (end -1.4795 -0.725) (layer "F.SilkS") (width 0.15))
    (fp_circle (center -1.499 1.236) (end -1.45 1.236) (layer "F.SilkS") (width 0.15) (fill solid))
    (fp_rect (start -1.65 -1.61) (end 1.65 1.61) (layer "F.CrtYd") (width 0.05) (fill none))
    (fp_line (start -1.102 0.916) (end 1.523 0.916) (layer "F.Fab") (width 0.15))
    (fp_line (start 1.523 -0.833) (end 1.523 0.916) (layer "F.Fab") (width 0.15))
    (fp_line (start -1.527 0.491) (end -1.527 -0.833) (layer "F.Fab") (width 0.15))
    (fp_line (start -1.527 -0.833) (end 1.523 -0.833) (layer "F.Fab") (width 0.15))
    (fp_line (start -1.527 0.491) (end -1.102 0.916) (layer "F.Fab") (width 0.15))
    (pad "1" smd rect (at -0.952 1.18 90) (size 0.7 0.8) (layers "F.Cu" "F.Paste" "F.Mask")
      (net 1 "GND") (pinfunction "GND") (pintype "power_in"))
    (pad "2" smd rect (at -0.001 1.18 90) (size 0.7 0.8) (layers "F.Cu" "F.Paste" "F.Mask")
      (net 363 "Net-(C138-Pad2)") (pinfunction "SW") (pintype "power_out"))
    (pad "3" smd rect (at 0.947 1.18 90) (size 0.7 0.8) (layers "F.Cu" "F.Paste" "F.Mask")
      (net 74 "VDD") (pinfunction "VIN") (pintype "power_in"))
    (pad "4" smd rect (at 0.947 -1.18 90) (size 0.7 0.8) (layers "F.Cu" "F.Paste" "F.Mask")
      (net 173 "Net-(R141-Pad2)") (pinfunction "FB") (pintype "input"))
    (pad "5" smd rect (at -0.001 -1.18 90) (size 0.7 0.8) (layers "F.Cu" "F.Paste" "F.Mask")
      (net 164 "/PSU/5V_DC_DC_ENABLE") (pinfunction "EN") (pintype "input"))
    (pad "6" smd rect (at -0.952 -1.18 90) (size 0.7 0.8) (layers "F.Cu" "F.Paste" "F.Mask")
      (net 362 "Net-(C138-Pad1)") (pinfunction "BST") (pintype "output"))
  )
	(footprint "sa800u-baseboard-hw-footprints:USB-C_12401610E4_2A" locked (layer "F.Cu")
    (tedit 6215EC4A)
    (at 115.75 147.95)
    (property "Author" "Antmicro")
    (property "License" "Apache-2.0")
    (property "MPN" "12401598E4#2A")
    (property "Manufacturer" "Amphenol")
    (property "Sheetfile" "usb-c-interface.kicad_sch")
    (property "Sheetname" "USB-C Interface ")
    (attr smd)
    (fp_text reference "J4" (at 3.27 -5.58) (layer "F.SilkS")
      (effects (font (size 0.7 0.7) (thickness 0.15)) (justify left bottom))
    )
    (fp_text value "12401598E4_2A" (at 0 6.549) (layer "F.Fab")
      (effects (font (size 0.7 0.7) (thickness 0.15)) (justify left bottom))
    )
    (fp_text user "License: Apache-2.0" (at -4.901 10.948) (layer "F.Fab") hide
      (effects (font (size 0.7 0.7) (thickness 0.15)) (justify left bottom))
    )
    (fp_text user "${REFERENCE}" (at -4.901 8.55) (layer "F.Fab") hide
      (effects (font (size 0.7 0.7) (thickness 0.15)) (justify left bottom))
    )
    (fp_text user "Author: Antmicro" (at -4.901 9.749) (layer "F.Fab") hide
      (effects (font (size 0.7 0.7) (thickness 0.15)) (justify left bottom))
    )
    (fp_line (start -4.601 5.448) (end -4.601 4.948) (layer "F.SilkS") (width 0.15))
    (fp_line (start 4.599 -5.25) (end 4.599 -4.75) (layer "F.SilkS") (width 0.15))
    (fp_line (start -4.601 -5.25) (end -4.1 -5.25) (layer "F.SilkS") (width 0.15))
    (fp_line (start 4.599 5.448) (end 4.599 4.948) (layer "F.SilkS") (width 0.15))
    (fp_line (start 4.599 -5.25) (end 4.099 -5.25) (layer "F.SilkS") (width 0.15))
    (fp_line (start 4.599 5.448) (end 4.099 5.448) (layer "F.SilkS") (width 0.15))
    (fp_line (start -4.601 5.448) (end -4.1 5.448) (layer "F.SilkS") (width 0.15))
    (fp_line (start -4.601 -5.25) (end -4.601 -4.75) (layer "F.SilkS") (width 0.15))
    (fp_circle (center -3.101 -5.25) (end -3.052 -5.25) (layer "F.SilkS") (width 0.15) (fill solid))
    (fp_rect (start -4.92 -5.46) (end 4.9 5.44) (layer "F.CrtYd") (width 0.05) (fill none))
    (fp_line (start -4.491 5.339) (end 4.49 5.339) (layer "F.Fab") (width 0.15))
    (fp_line (start -4.491 -5.162) (end 4.49 -5.162) (layer "F.Fab") (width 0.15))
    (fp_line (start -4.491 -5.162) (end -4.491 5.339) (layer "F.Fab") (width 0.15))
    (fp_line (start 4.49 -5.162) (end 4.49 5.339) (layer "F.Fab") (width 0.15))
    (pad "" np_thru_hole circle locked (at -3.601 -4.25) (size 0.65 0.65) (drill 0.65) (layers *.Cu *.Mask))
    (pad "" np_thru_hole oval locked (at 3.6 -4.25) (size 0.95 0.65) (drill oval 0.95 0.65) (layers *.Cu *.Mask))
    (pad "A1" smd rect locked (at -2.75 -4.912) (size 0.3 0.7) (layers "F.Cu" "F.Paste" "F.Mask")
      (net 1 "GND") (pintype "passive"))
    (pad "A2" smd rect locked (at -2.25 -4.912) (size 0.3 0.7) (layers "F.Cu" "F.Paste" "F.Mask")
      (net 215 "/USB-C Interface /USB2C_TX1_C_P") (pintype "passive"))
    (pad "A3" smd rect locked (at -1.75 -4.912) (size 0.3 0.7) (layers "F.Cu" "F.Paste" "F.Mask")
      (net 211 "/USB-C Interface /USB2C_TX1_C_N") (pintype "passive"))
    (pad "A4" smd rect locked (at -1.25 -4.912) (size 0.3 0.7) (layers "F.Cu" "F.Paste" "F.Mask")
      (net 210 "/USB-C Interface /USB2_5V") (pintype "passive"))
    (pad "A5" smd rect locked (at -0.75 -4.912) (size 0.3 0.7) (layers "F.Cu" "F.Paste" "F.Mask")
      (net 265 "/USB-C Interface /USB2_CC1") (pintype "passive"))
    (pad "A6" smd rect locked (at -0.25 -4.912) (size 0.3 0.7) (layers "F.Cu" "F.Paste" "F.Mask")
      (net 80 "USB2C_HS_D_P") (pintype "passive"))
    (pad "A7" smd rect locked (at 0.247 -4.912) (size 0.3 0.7) (layers "F.Cu" "F.Paste" "F.Mask")
      (net 79 "USB2C_HS_D_N") (pintype "passive"))
    (pad "A8" smd rect locked (at 0.747 -4.912) (size 0.3 0.7) (layers "F.Cu" "F.Paste" "F.Mask")
      (net 426 "unconnected-(J4-PadA8)") (pintype "passive+no_connect"))
    (pad "A9" smd rect locked (at 1.249 -4.912) (size 0.3 0.7) (layers "F.Cu" "F.Paste" "F.Mask")
      (net 210 "/USB-C Interface /USB2_5V") (pintype "passive"))
    (pad "A10" smd rect locked (at 1.749 -4.912) (size 0.3 0.7) (layers "F.Cu" "F.Paste" "F.Mask")
      (net 217 "/USB-C Interface /USB2C_RX2_C_N") (pintype "passive"))
    (pad "A11" smd rect locked (at 2.249 -4.912) (size 0.3 0.7) (layers "F.Cu" "F.Paste" "F.Mask")
      (net 213 "/USB-C Interface /USB2C_RX2_C_P") (pintype "passive"))
    (pad "A12" smd rect locked (at 2.749 -4.912) (size 0.3 0.7) (layers "F.Cu" "F.Paste" "F.Mask")
      (net 1 "GND") (pintype "passive"))
    (pad "B1" smd rect locked (at 2.499 -3.21) (size 0.3 0.7) (layers "F.Cu" "F.Paste" "F.Mask")
      (net 1 "GND") (pintype "passive"))
    (pad "B2" smd rect locked (at 1.999 -3.21) (size 0.3 0.7) (layers "F.Cu" "F.Paste" "F.Mask")
      (net 222 "/USB-C Interface /USB2C_TX2_C_P") (pintype "passive"))
    (pad "B3" smd rect locked (at 1.499 -3.21) (size 0.3 0.7) (layers "F.Cu" "F.Paste" "F.Mask")
      (net 226 "/USB-C Interface /USB2C_TX2_C_N") (pintype "passive"))
    (pad "B4" smd rect locked (at 0.997 -3.21) (size 0.3 0.7) (layers "F.Cu" "F.Paste" "F.Mask")
      (net 210 "/USB-C Interface /USB2_5V") (pintype "passive"))
    (pad "B5" smd rect locked (at 0.497 -3.21) (size 0.3 0.7) (layers "F.Cu" "F.Paste" "F.Mask")
      (net 264 "/USB-C Interface /USB2_CC2") (pintype "passive"))
    (pad "B6" smd rect locked (at 0 -3.21) (size 0.3 0.7) (layers "F.Cu" "F.Paste" "F.Mask")
      (net 80 "USB2C_HS_D_P") (pintype "passive"))
    (pad "B7" smd rect locked (at -0.5 -3.21) (size 0.3 0.7) (layers "F.Cu" "F.Paste" "F.Mask")
      (net 79 "USB2C_HS_D_N") (pintype "passive"))
    (pad "B8" smd rect locked (at -1 -3.21) (size 0.3 0.7) (layers "F.Cu" "F.Paste" "F.Mask")
      (net 425 "unconnected-(J4-PadB8)") (pintype "passive+no_connect"))
    (pad "B9" smd rect locked (at -1.5 -3.21) (size 0.3 0.7) (layers "F.Cu" "F.Paste" "F.Mask")
      (net 210 "/USB-C Interface /USB2_5V") (pintype "passive"))
    (pad "B10" smd rect locked (at -2 -3.21) (size 0.3 0.7) (layers "F.Cu" "F.Paste" "F.Mask")
      (net 220 "/USB-C Interface /USB2C_RX1_C_N") (pintype "passive"))
    (pad "B11" smd rect locked (at -2.5 -3.21) (size 0.3 0.7) (layers "F.Cu" "F.Paste" "F.Mask")
      (net 224 "/USB-C Interface /USB2C_RX1_C_P") (pintype "passive"))
    (pad "B12" smd rect locked (at -3 -3.21) (size 0.3 0.7) (layers "F.Cu" "F.Paste" "F.Mask")
      (net 1 "GND") (pintype "passive"))
    (pad "SH" thru_hole oval locked (at 4.49 2.95) (size 0.85 1.45) (drill oval 0.5 1.1) (layers *.Cu *.Mask)
      (net 1 "GND") (pintype "input"))
    (pad "SH" thru_hole oval locked (at 4.128 -3.001) (size 0.85 1.45) (drill oval 0.5 1.1) (layers *.Cu *.Mask)
      (net 1 "GND") (pintype "input"))
    (pad "SH" thru_hole oval locked (at -4.491 2.95) (size 0.85 1.45) (drill oval 0.5 1.1) (layers *.Cu *.Mask)
      (net 1 "GND") (pintype "input"))
    (pad "SH" thru_hole oval locked (at -4.13 -3.001) (size 0.85 1.45) (drill oval 0.5 1.1) (layers *.Cu *.Mask)
      (net 1 "GND") (pintype "input"))
  )
	(footprint "sa800u-baseboard-hw-footprints:USB-C_12401610E4_2A" (layer "F.Cu")
    (tedit 6215EC4A)
    (at 101.75 147.95)
    (property "Author" "Antmicro")
    (property "License" "Apache-2.0")
    (property "MPN" "12401598E4#2A")
    (property "Manufacturer" "Amphenol")
    (property "Sheetfile" "usb-c-interface.kicad_sch")
    (property "Sheetname" "USB-C Interface ")
    (attr smd)
    (fp_text reference "J3" (at 3.45 -5.62) (layer "F.SilkS")
      (effects (font (size 0.7 0.7) (thickness 0.15)) (justify left bottom))
    )
    (fp_text value "12401598E4_2A" (at 0 6.549) (layer "F.Fab")
      (effects (font (size 0.7 0.7) (thickness 0.15)) (justify left bottom))
    )
    (fp_text user "Author: Antmicro" (at -4.901 9.749) (layer "F.Fab") hide
      (effects (font (size 0.7 0.7) (thickness 0.15)) (justify left bottom))
    )
    (fp_text user "License: Apache-2.0" (at -4.901 10.948) (layer "F.Fab") hide
      (effects (font (size 0.7 0.7) (thickness 0.15)) (justify left bottom))
    )
    (fp_text user "${REFERENCE}" (at -4.901 8.55) (layer "F.Fab") hide
      (effects (font (size 0.7 0.7) (thickness 0.15)) (justify left bottom))
    )
    (fp_line (start 4.599 5.448) (end 4.099 5.448) (layer "F.SilkS") (width 0.15))
    (fp_line (start 4.599 -5.25) (end 4.599 -4.75) (layer "F.SilkS") (width 0.15))
    (fp_line (start -4.601 5.448) (end -4.601 4.948) (layer "F.SilkS") (width 0.15))
    (fp_line (start -4.601 -5.25) (end -4.1 -5.25) (layer "F.SilkS") (width 0.15))
    (fp_line (start -4.601 -5.25) (end -4.601 -4.75) (layer "F.SilkS") (width 0.15))
    (fp_line (start 4.599 -5.25) (end 4.099 -5.25) (layer "F.SilkS") (width 0.15))
    (fp_line (start -4.601 5.448) (end -4.1 5.448) (layer "F.SilkS") (width 0.15))
    (fp_line (start 4.599 5.448) (end 4.599 4.948) (layer "F.SilkS") (width 0.15))
    (fp_circle (center -3.101 -5.25) (end -3.052 -5.25) (layer "F.SilkS") (width 0.15) (fill solid))
    (fp_rect (start -4.92 -5.46) (end 4.9 5.44) (layer "F.CrtYd") (width 0.05) (fill none))
    (fp_line (start -4.491 5.339) (end 4.49 5.339) (layer "F.Fab") (width 0.15))
    (fp_line (start -4.491 -5.162) (end 4.49 -5.162) (layer "F.Fab") (width 0.15))
    (fp_line (start -4.491 -5.162) (end -4.491 5.339) (layer "F.Fab") (width 0.15))
    (fp_line (start 4.49 -5.162) (end 4.49 5.339) (layer "F.Fab") (width 0.15))
    (pad "" np_thru_hole circle (at -3.601 -4.25) (size 0.65 0.65) (drill 0.65) (layers *.Cu *.Mask))
    (pad "" np_thru_hole oval (at 3.6 -4.25) (size 0.95 0.65) (drill oval 0.95 0.65) (layers *.Cu *.Mask))
    (pad "A1" smd rect (at -2.75 -4.912) (size 0.3 0.7) (layers "F.Cu" "F.Paste" "F.Mask")
      (net 1 "GND") (pintype "passive"))
    (pad "A2" smd rect (at -2.25 -4.912) (size 0.3 0.7) (layers "F.Cu" "F.Paste" "F.Mask")
      (net 302 "/USB-C Interface /USB1C_TX0_C_P") (pintype "passive"))
    (pad "A3" smd rect (at -1.75 -4.912) (size 0.3 0.7) (layers "F.Cu" "F.Paste" "F.Mask")
      (net 303 "/USB-C Interface /USB1C_TX0_C_N") (pintype "passive"))
    (pad "A4" smd rect (at -1.25 -4.912) (size 0.3 0.7) (layers "F.Cu" "F.Paste" "F.Mask")
      (net 66 "USB_VBUS") (pintype "passive"))
    (pad "A5" smd rect (at -0.75 -4.912) (size 0.3 0.7) (layers "F.Cu" "F.Paste" "F.Mask")
      (net 326 "USB_CC1") (pintype "passive"))
    (pad "A6" smd rect (at -0.25 -4.912) (size 0.3 0.7) (layers "F.Cu" "F.Paste" "F.Mask")
      (net 321 "USB1_D_P") (pintype "passive"))
    (pad "A7" smd rect (at 0.247 -4.912) (size 0.3 0.7) (layers "F.Cu" "F.Paste" "F.Mask")
      (net 322 "USB1_D_N") (pintype "passive"))
    (pad "A8" smd rect (at 0.747 -4.912) (size 0.3 0.7) (layers "F.Cu" "F.Paste" "F.Mask")
      (net 330 "/USB-C Interface /USB1_SBU_N") (pintype "passive"))
    (pad "A9" smd rect (at 1.249 -4.912) (size 0.3 0.7) (layers "F.Cu" "F.Paste" "F.Mask")
      (net 66 "USB_VBUS") (pintype "passive"))
    (pad "A10" smd rect (at 1.749 -4.912) (size 0.3 0.7) (layers "F.Cu" "F.Paste" "F.Mask")
      (net 304 "/USB-C Interface /USB1C_RX1_C_N") (pintype "passive"))
    (pad "A11" smd rect (at 2.249 -4.912) (size 0.3 0.7) (layers "F.Cu" "F.Paste" "F.Mask")
      (net 305 "/USB-C Interface /USB1C_RX1_C_P") (pintype "passive"))
    (pad "A12" smd rect (at 2.749 -4.912) (size 0.3 0.7) (layers "F.Cu" "F.Paste" "F.Mask")
      (net 1 "GND") (pintype "passive"))
    (pad "B1" smd rect (at 2.499 -3.21) (size 0.3 0.7) (layers "F.Cu" "F.Paste" "F.Mask")
      (net 1 "GND") (pintype "passive"))
    (pad "B2" smd rect (at 1.999 -3.21) (size 0.3 0.7) (layers "F.Cu" "F.Paste" "F.Mask")
      (net 307 "/USB-C Interface /USB1C_TX1_C_P") (pintype "passive"))
    (pad "B3" smd rect (at 1.499 -3.21) (size 0.3 0.7) (layers "F.Cu" "F.Paste" "F.Mask")
      (net 306 "/USB-C Interface /USB1C_TX1_C_N") (pintype "passive"))
    (pad "B4" smd rect (at 0.997 -3.21) (size 0.3 0.7) (layers "F.Cu" "F.Paste" "F.Mask")
      (net 66 "USB_VBUS") (pintype "passive"))
    (pad "B5" smd rect (at 0.497 -3.21) (size 0.3 0.7) (layers "F.Cu" "F.Paste" "F.Mask")
      (net 327 "USB_CC2") (pintype "passive"))
    (pad "B6" smd rect (at 0 -3.21) (size 0.3 0.7) (layers "F.Cu" "F.Paste" "F.Mask")
      (net 321 "USB1_D_P") (pintype "passive"))
    (pad "B7" smd rect (at -0.5 -3.21) (size 0.3 0.7) (layers "F.Cu" "F.Paste" "F.Mask")
      (net 322 "USB1_D_N") (pintype "passive"))
    (pad "B8" smd rect (at -1 -3.21) (size 0.3 0.7) (layers "F.Cu" "F.Paste" "F.Mask")
      (net 331 "/USB-C Interface /USB1_SBU_P") (pintype "passive"))
    (pad "B9" smd rect (at -1.5 -3.21) (size 0.3 0.7) (layers "F.Cu" "F.Paste" "F.Mask")
      (net 66 "USB_VBUS") (pintype "passive"))
    (pad "B10" smd rect (at -2 -3.21) (size 0.3 0.7) (layers "F.Cu" "F.Paste" "F.Mask")
      (net 323 "/USB-C Interface /USB1C_RX0_C_N") (pintype "passive"))
    (pad "B11" smd rect (at -2.5 -3.21) (size 0.3 0.7) (layers "F.Cu" "F.Paste" "F.Mask")
      (net 308 "/USB-C Interface /USB1C_RX0_C_P") (pintype "passive"))
    (pad "B12" smd rect (at -3 -3.21) (size 0.3 0.7) (layers "F.Cu" "F.Paste" "F.Mask")
      (net 1 "GND") (pintype "passive"))
    (pad "SH" thru_hole oval (at 4.49 2.95) (size 0.85 1.45) (drill oval 0.5 1.1) (layers *.Cu *.Mask)
      (net 1 "GND") (pintype "input"))
    (pad "SH" thru_hole oval (at -4.491 2.95) (size 0.85 1.45) (drill oval 0.5 1.1) (layers *.Cu *.Mask)
      (net 1 "GND") (pintype "input"))
    (pad "SH" thru_hole oval (at 4.128 -3.001) (size 0.85 1.45) (drill oval 0.5 1.1) (layers *.Cu *.Mask)
      (net 1 "GND") (pintype "input"))
    (pad "SH" thru_hole oval (at -4.13 -3.001) (size 0.85 1.45) (drill oval 0.5 1.1) (layers *.Cu *.Mask)
      (net 1 "GND") (pintype "input"))
  )
	(footprint "sa800u-baseboard-hw-footprints:C_0402_1005Metric" (layer "F.Cu")
    (tedit 616D63CF)
    (at 132.9 138.9)
    (descr "Capacitor SMD 0402")
    (tags "capacitor SMD 0402")
    (property "Author" "Antmicro")
    (property "Dielectric" "X5R")
    (property "License" "Apache-2.0")
    (property "MPN" "GRM155R61H104KE14D")
    (property "Manufacturer" "Murata")
    (property "Sheetfile" "usb-c-interface.kicad_sch")
    (property "Sheetname" "USB-C Interface ")
    (property "Val" "100n")
    (property "Voltage" "50V")
    (attr smd)
    (fp_text reference "C67" (at -1.14 1.36) (layer "F.SilkS")
      (effects (font (size 0.7 0.7) (thickness 0.15)) (justify left bottom))
    )
    (fp_text value "C_100n_0402" (at 0 1.4) (layer "F.Fab")
      (effects (font (size 0.7 0.7) (thickness 0.15)) (justify left bottom))
    )
    (fp_text user "Author: Antmicro" (at -0.932 4.17) (layer "F.Fab") hide
      (effects (font (size 0.7 0.7) (thickness 0.15)) (justify left bottom))
    )
    (fp_text user "License: Apache-2.0" (at -0.932 5.17) (layer "F.Fab") hide
      (effects (font (size 0.7 0.7) (thickness 0.15)) (justify left bottom))
    )
    (fp_text user "${REFERENCE}" (at -0.932 3.168) (layer "F.Fab") hide
      (effects (font (size 0.7 0.7) (thickness 0.15)) (justify left bottom))
    )
    (fp_rect (start -0.94 -0.47) (end 0.94 0.47) (layer "F.CrtYd") (width 0.05) (fill none))
    (fp_rect (start -0.499 -0.249) (end 0.499 0.249) (layer "F.Fab") (width 0.15) (fill none))
    (pad "1" smd roundrect (at -0.484 0) (size 0.59 0.64) (layers "F.Cu" "F.Paste" "F.Mask") (roundrect_rratio 0.25)
      (net 352 "Net-(C67-Pad1)") (pintype "passive"))
    (pad "2" smd roundrect (at 0.484 0) (size 0.59 0.64) (layers "F.Cu" "F.Paste" "F.Mask") (roundrect_rratio 0.25)
      (net 1 "GND") (pintype "passive"))
  )
)
